# T6G (Grand Teton) — schematic netlist excerpt (pin names and nets, part order shuffled) for the footprints in the layout excerpt that follows; sources: Cadence DE-HDL packaged netlist, KiCad conversion of 04192023_DAF0TMB3IC0_F0TG_MB_C_brd_V02_OCP.brd

PC166_1  Q_CAP  22UF 4V 20% X6S  pkg C0805  page 205 : A = PVDDIO_P0 ; B = GND
R3502  Q_RES  100K 1% EMPTY  pkg 0402LF  page 126 : A = GPU_FPGA_EROT_FATALERR_N ; B = GND

(kicad_pcb
	(version 20260206)
	(generator "pcbnew")
	(generator_version "10.0")
	(general
		(thickness 1.6)
		(legacy_teardrops no)
	)
	(paper "A4")
	(title_block
		(title "04192023_DAF0TMB3IC0_F0TG_MB_C_brd_V02_OCP.brd")
		(comment 1 "Grand Teton / footprints 5771-5773 of 8354")
	)
	(layers
		(0 "F.Cu" signal "TOP")
		(4 "In1.Cu" signal "GND")
		(6 "In2.Cu" signal "IN1")
		(8 "In3.Cu" signal "GND1")
		(10 "In4.Cu" signal "IN2")
		(12 "In5.Cu" signal "GND2")
		(14 "In6.Cu" signal "IN3")
		(16 "In7.Cu" signal "GND3")
		(18 "In8.Cu" signal "VCC")
		(20 "In9.Cu" signal "VCC1")
		(22 "In10.Cu" signal "GND4")
		(24 "In11.Cu" signal "IN4")
		(26 "In12.Cu" signal "GND5")
		(28 "In13.Cu" signal "IN5")
		(30 "In14.Cu" signal "GND6")
		(32 "In15.Cu" signal "IN6")
		(34 "In16.Cu" signal "GND7")
		(2 "B.Cu" signal "BOTTOM")
		(9 "F.Adhes" user "F.Adhesive")
		(11 "B.Adhes" user "B.Adhesive")
		(13 "F.Paste" user "Package Geometry/Pastemask Top")
		(15 "B.Paste" user "Package Geometry/Pastemask Bottom")
		(5 "F.SilkS" user "Ref Des/Silkscreen Top")
		(7 "B.SilkS" user "Ref Des/Silkscreen Bottom")
		(1 "F.Mask" user "Board Geometry/Soldermask Top")
		(3 "B.Mask" user "Board Geometry/Soldermask Bottom")
		(17 "Dwgs.User" user "User.Drawings")
		(19 "Cmts.User" user "User.Comments")
		(21 "Eco1.User" user "User.Eco1")
		(23 "Eco2.User" user "User.Eco2")
		(25 "Edge.Cuts" user "Board Geometry/Outline")
		(27 "Margin" user)
		(31 "F.CrtYd" user "Package Geometry/Place Bound Top")
		(29 "B.CrtYd" user "Package Geometry/Place Bound Bottom")
		(35 "F.Fab" user "Ref Des/Assembly Top")
		(33 "B.Fab" user "Ref Des/Assembly Bottom")
	)
	(footprint ""
		(layer "B.Cu")
		(at 296.222928 -337.980528 -90)
		(property "Reference" "PC166_1"
			(at 0 0 90)
			(layer "B.SilkS")
			(hide yes)
			(effects
				(font
					(size 1.27 1.27)
				)
				(justify mirror)
			)
		)
		(property "Value" ""
			(at 0 0 90)
			(layer "B.Fab")
			(effects
				(font
					(size 1.27 1.27)
				)
				(justify mirror)
			)
		)
		(duplicate_pad_numbers_are_jumpers no)
		(fp_line
			(start -1.524 0.762)
			(end 1.524 0.762)
			(stroke
				(width 0.1524)
				(type default)
			)
			(layer "B.SilkS")
		)
		(fp_line
			(start 1.524 0.762)
			(end 1.524 -0.762)
			(stroke
				(width 0.1524)
				(type default)
			)
			(layer "B.SilkS")
		)
		(fp_line
			(start -1.524 -0.762)
			(end -1.524 0.762)
			(stroke
				(width 0.1524)
				(type default)
			)
			(layer "B.SilkS")
		)
		(fp_line
			(start 1.524 -0.762)
			(end -1.524 -0.762)
			(stroke
				(width 0.1524)
				(type default)
			)
			(layer "B.SilkS")
		)
		(fp_line
			(start -1.1049 0.724916)
			(end -1.1049 -0.724916)
			(stroke
				(width 0.1)
				(type default)
			)
			(layer "B.Fab")
		)
		(fp_line
			(start 1.1049 0.724916)
			(end -1.1049 0.724916)
			(stroke
				(width 0.1)
				(type default)
			)
			(layer "B.Fab")
		)
		(fp_line
			(start -1.1049 -0.724916)
			(end 1.1049 -0.724916)
			(stroke
				(width 0.1)
				(type default)
			)
			(layer "B.Fab")
		)
		(fp_line
			(start 1.1049 -0.724916)
			(end 1.1049 0.724916)
			(stroke
				(width 0.1)
				(type default)
			)
			(layer "B.Fab")
		)
		(pad "1" smd rect
			(at 0.889 0 270)
			(size 1.016 1.27)
			(layers "B.Cu" "B.Mask" "B.Paste")
			(net "PVDDIO_P0")
		)
		(pad "2" smd rect
			(at -0.889 0 270)
			(size 1.016 1.27)
			(layers "B.Cu" "B.Mask" "B.Paste")
			(net "GND")
		)
	)
	(footprint ""
		(layer "B.Cu")
		(at 117.094 -417.957 -90)
		(property "Reference" "R3502"
			(at 0 0 90)
			(layer "B.SilkS")
			(hide yes)
			(effects
				(font
					(size 1.27 1.27)
				)
				(justify mirror)
			)
		)
		(property "Value" ""
			(at 0 0 90)
			(layer "B.Fab")
			(effects
				(font
					(size 1.27 1.27)
				)
				(justify mirror)
			)
		)
		(duplicate_pad_numbers_are_jumpers no)
		(fp_line
			(start -0.7874 0.4064)
			(end 0.7874 0.4064)
			(stroke
				(width 0.1524)
				(type default)
			)
			(layer "B.SilkS")
		)
		(fp_line
			(start 0.7874 0.4064)
			(end 0.7874 -0.4064)
			(stroke
				(width 0.1524)
				(type default)
			)
			(layer "B.SilkS")
		)
		(fp_line
			(start -0.7874 -0.4064)
			(end -0.7874 0.4064)
			(stroke
				(width 0.1524)
				(type default)
			)
			(layer "B.SilkS")
		)
		(fp_line
			(start 0.7874 -0.4064)
			(end -0.7874 -0.4064)
			(stroke
				(width 0.1524)
				(type default)
			)
			(layer "B.SilkS")
		)
		(fp_line
			(start -0.67945 0.3048)
			(end -0.120396 0.3048)
			(stroke
				(width 0.1)
				(type default)
			)
			(layer "B.Fab")
		)
		(fp_line
			(start -0.120396 0.3048)
			(end -0.120396 0.2794)
			(stroke
				(width 0.1)
				(type default)
			)
			(layer "B.Fab")
		)
		(fp_line
			(start 0.12065 0.3048)
			(end 0.67945 0.3048)
			(stroke
				(width 0.1)
				(type default)
			)
			(layer "B.Fab")
		)
		(fp_line
			(start 0.67945 0.3048)
			(end 0.67945 -0.305054)
			(stroke
				(width 0.1)
				(type default)
			)
			(layer "B.Fab")
		)
		(fp_line
			(start -0.120396 0.2794)
			(end 0.12065 0.2794)
			(stroke
				(width 0.1)
				(type default)
			)
			(layer "B.Fab")
		)
		(fp_line
			(start 0.12065 0.2794)
			(end 0.12065 0.3048)
			(stroke
				(width 0.1)
				(type default)
			)
			(layer "B.Fab")
		)
		(fp_line
			(start -0.12065 -0.2794)
			(end -0.12065 -0.3048)
			(stroke
				(width 0.1)
				(type default)
			)
			(layer "B.Fab")
		)
		(fp_line
			(start 0.12065 -0.2794)
			(end -0.12065 -0.2794)
			(stroke
				(width 0.1)
				(type default)
			)
			(layer "B.Fab")
		)
		(fp_line
			(start -0.67945 -0.3048)
			(end -0.67945 0.3048)
			(stroke
				(width 0.1)
				(type default)
			)
			(layer "B.Fab")
		)
		(fp_line
			(start -0.12065 -0.3048)
			(end -0.67945 -0.3048)
			(stroke
				(width 0.1)
				(type default)
			)
			(layer "B.Fab")
		)
		(fp_line
			(start 0.12065 -0.305054)
			(end 0.12065 -0.2794)
			(stroke
				(width 0.1)
				(type default)
			)
			(layer "B.Fab")
		)
		(fp_line
			(start 0.67945 -0.305054)
			(end 0.12065 -0.305054)
			(stroke
				(width 0.1)
				(type default)
			)
			(layer "B.Fab")
		)
		(pad "1" smd circle
			(at 0.40005 0 90)
			(size 0 0)
			(layers "B.Cu" "B.Mask" "B.Paste")
			(net "GPU_FPGA_EROT_FATALERR_N")
		)
		(pad "2" smd circle
			(at -0.40005 0 90)
			(size 0 0)
			(layers "B.Cu" "B.Mask" "B.Paste")
			(net "GND")
		)
	)
	(footprint ""
		(layer "B.Cu")
		(at 249.428 -246.634)
		(property "Reference" "ME14"
			(at 0 0 0)
			(layer "B.SilkS")
			(hide yes)
			(effects
				(font
					(size 1.27 1.27)
				)
				(justify mirror)
			)
		)
		(property "Value" ""
			(at 0 0 0)
			(layer "B.Fab")
			(effects
				(font
					(size 1.27 1.27)
				)
				(justify mirror)
			)
		)
		(duplicate_pad_numbers_are_jumpers no)
		(zone
			(layer "B.Cu")
			(hatch none 0.5)
			(connect_pads
				(clearance 0)
			)
			(min_thickness 0.25)
			(keepout
				(tracks allowed)
				(vias allowed)
				(pads allowed)
				(copperpour allowed)
				(footprints not_allowed)
			)
			(placement
				(enabled no)
				(sheetname "")
			)
			(fill
				(thermal_gap 0.5)
				(thermal_bridge_width 0.5)
				(island_removal_mode 0)
			)
			(polygon
				(pts
					(arc
						(start 259.42798 -246.634)
						(mid 239.42802 -246.634)
						(end 259.42798 -246.634)
					)
				)
			)
		)
	)
)
